# BASEBOARD_FAB2 (Tioga Pass) — schematic netlist excerpt (pin names and nets, part order shuffled) for the footprints in the layout excerpt that follows; sources: Cadence DE-HDL packaged netlist, KiCad conversion of Wiwynn_Tioga_Pass_MB.brd

C8F14  ST470U6D3VDM-7-GP  IRP=1.7A  pkg SMD-TCG4  page 240 : \1\ = P3V3_STBY ; \2\ = GND
R25W51  120R2F-GP  1%  pkg RCL_GP  page 151 : \1\ = BMC_M_A13 ; \2\ = P1V2_AUX_BMC

(kicad_pcb
	(version 20260206)
	(generator "pcbnew")
	(generator_version "10.0")
	(general
		(thickness 1.6)
		(legacy_teardrops no)
	)
	(paper "A4")
	(title_block
		(title "Wiwynn_Tioga_Pass_MB.brd")
		(comment 1 "Tioga Pass / footprints 2056-2057 of 4770")
	)
	(layers
		(0 "F.Cu" signal "TOP")
		(4 "In1.Cu" signal "L2GND")
		(6 "In2.Cu" signal "L3")
		(8 "In3.Cu" signal "L4GND")
		(10 "In4.Cu" signal "L5")
		(12 "In5.Cu" signal "L6GND")
		(14 "In6.Cu" signal "L7VCC")
		(16 "In7.Cu" signal "L8VCC")
		(18 "In8.Cu" signal "L9GND")
		(20 "In9.Cu" signal "L10")
		(22 "In10.Cu" signal "L11GND")
		(24 "In11.Cu" signal "L12")
		(26 "In12.Cu" signal "L13GND")
		(2 "B.Cu" signal "BOTTOM")
		(9 "F.Adhes" user "F.Adhesive")
		(11 "B.Adhes" user "B.Adhesive")
		(13 "F.Paste" user "Package Geometry/Pastemask Top")
		(15 "B.Paste" user "Package Geometry/Pastemask Bottom")
		(5 "F.SilkS" user "Ref Des/Silkscreen Top")
		(7 "B.SilkS" user "Ref Des/Silkscreen Bottom")
		(1 "F.Mask" user "Board Geometry/Soldermask Top")
		(3 "B.Mask" user "Board Geometry/Soldermask Bottom")
		(17 "Dwgs.User" user "User.Drawings")
		(19 "Cmts.User" user "User.Comments")
		(21 "Eco1.User" user "User.Eco1")
		(23 "Eco2.User" user "User.Eco2")
		(25 "Edge.Cuts" user "Board Geometry/Outline")
		(27 "Margin" user)
		(31 "F.CrtYd" user "Package Geometry/Place Bound Top")
		(29 "B.CrtYd" user "Package Geometry/Place Bound Bottom")
		(35 "F.Fab" user "Ref Des/Assembly Top")
		(33 "B.Fab" user "Ref Des/Assembly Bottom")
	)
	(footprint ""
		(layer "F.Cu")
		(at 459.3844 -15.3924)
		(property "Reference" "C8F14"
			(at 0 0 0)
			(layer "F.SilkS")
			(hide yes)
			(effects
				(font
					(size 1.27 1.27)
				)
			)
		)
		(property "Value" "*"
			(at 0 -9.7155 0)
			(unlocked yes)
			(layer "F.Fab")
			(hide yes)
			(effects
				(font
					(size 1.27 1.016)
					(thickness 0.1524)
				)
			)
		)
		(property "Device Type" "ST470U6D3VDM-7-GP_SMD-TCG4-ST4A"
			(at 0 -11.2395 0)
			(unlocked yes)
			(layer "F.Fab")
			(hide yes)
			(effects
				(font
					(size 1.27 1.016)
					(thickness 0.1524)
				)
			)
		)
		(duplicate_pad_numbers_are_jumpers no)
		(fp_line
			(start -2.286 -4.8768)
			(end -2.286 -2.032)
			(stroke
				(width 0.1524)
				(type default)
			)
			(layer "F.SilkS")
		)
		(fp_line
			(start -2.286 4.8768)
			(end -2.286 2.032)
			(stroke
				(width 0.1524)
				(type default)
			)
			(layer "F.SilkS")
		)
		(fp_line
			(start 2.1082 -4.699)
			(end -2.1082 -4.699)
			(stroke
				(width 0.508)
				(type default)
			)
			(layer "F.SilkS")
		)
		(fp_line
			(start 2.286 -4.8768)
			(end -2.286 -4.8768)
			(stroke
				(width 0.1524)
				(type default)
			)
			(layer "F.SilkS")
		)
		(fp_line
			(start 2.286 -2.032)
			(end 2.286 -4.8768)
			(stroke
				(width 0.1524)
				(type default)
			)
			(layer "F.SilkS")
		)
		(fp_line
			(start 2.286 2.032)
			(end 2.286 4.8768)
			(stroke
				(width 0.1524)
				(type default)
			)
			(layer "F.SilkS")
		)
		(fp_line
			(start 2.286 4.8768)
			(end -2.286 4.8768)
			(stroke
				(width 0.1524)
				(type default)
			)
			(layer "F.SilkS")
		)
		(fp_rect
			(start -2.1463 3.6449)
			(end 2.1463 -3.6449)
			(stroke
				(width 0)
				(type default)
			)
			(fill no)
			(layer "F.CrtYd")
		)
		(fp_poly
			(pts
				(xy -2.54 4.953) (xy -2.54 4.2926) (xy -3.81 4.2926) (xy -3.81 -4.2926) (xy -2.54 -4.2926) (xy -2.54 -4.953)
				(xy 2.54 -4.953) (xy 2.54 -4.2926) (xy 3.81 -4.2926) (xy 3.81 -1.6256) (xy 2.1463 -1.6256) (xy 2.1463 -3.6449)
				(xy -2.1463 -3.6449) (xy -2.1463 3.6449) (xy 2.1463 3.6449) (xy 2.1463 -1.6129) (xy 3.81 -1.6129)
				(xy 3.81 4.2926) (xy 2.54 4.2926) (xy 2.54 4.953)
			)
			(stroke
				(width 0)
				(type default)
			)
			(fill no)
			(layer "F.CrtYd")
		)
		(fp_rect
			(start -3.81 4.2926)
			(end -2.54 -4.2926)
			(stroke
				(width 0)
				(type default)
			)
			(fill no)
			(layer "F.Fab")
		)
		(fp_rect
			(start -2.54 4.953)
			(end 2.54 -4.953)
			(stroke
				(width 0)
				(type default)
			)
			(fill no)
			(layer "F.Fab")
		)
		(fp_rect
			(start 2.54 4.2926)
			(end 3.81 -4.2926)
			(stroke
				(width 0)
				(type default)
			)
			(fill no)
			(layer "F.Fab")
		)
		(pad "1" smd rect
			(at 0 -3.1496)
			(size 2.413 2.286)
			(layers "F.Cu" "F.Mask" "F.Paste")
			(net "P3V3_STBY")
		)
		(pad "2" smd rect
			(at 0 3.1496)
			(size 2.413 2.286)
			(layers "F.Cu" "F.Mask" "F.Paste")
			(net "GND")
		)
		(zone
			(layer "F.Cu")
			(hatch none 0.5)
			(connect_pads
				(clearance 0)
			)
			(min_thickness 0.25)
			(keepout
				(tracks allowed)
				(vias not_allowed)
				(pads allowed)
				(copperpour not_allowed)
				(footprints allowed)
			)
			(placement
				(enabled no)
				(sheetname "")
			)
			(fill
				(thermal_gap 0.5)
				(thermal_bridge_width 0.5)
				(island_removal_mode 0)
			)
			(polygon
				(pts
					(xy 457.8731 -10.795) (xy 460.8957 -10.795) (xy 460.8957 -13.6906) (xy 460.8957 -14.0208) (xy 457.8731 -14.0208)
					(xy 457.8731 -13.6906)
				)
			)
		)
		(zone
			(layer "F.Cu")
			(hatch none 0.5)
			(connect_pads
				(clearance 0)
			)
			(min_thickness 0.25)
			(keepout
				(tracks allowed)
				(vias not_allowed)
				(pads allowed)
				(copperpour not_allowed)
				(footprints allowed)
			)
			(placement
				(enabled no)
				(sheetname "")
			)
			(fill
				(thermal_gap 0.5)
				(thermal_bridge_width 0.5)
				(island_removal_mode 0)
			)
			(polygon
				(pts
					(xy 460.8957 -17.0815) (xy 460.8957 -19.9898) (xy 457.8731 -19.9898) (xy 457.8731 -17.0942) (xy 457.8731 -16.764)
					(xy 460.8957 -16.764)
				)
			)
		)
	)
	(footprint ""
		(layer "F.Cu")
		(at 437.690006 -43.568874 180)
		(property "Reference" "R25W51"
			(at 0 0 180)
			(layer "F.SilkS")
			(hide yes)
			(effects
				(font
					(size 1.27 1.27)
				)
			)
		)
		(property "Value" "*"
			(at 0.064008 -4.108196 180)
			(unlocked yes)
			(layer "F.Fab")
			(hide yes)
			(effects
				(font
					(size 1.27 1.016)
					(thickness 0.1524)
				)
			)
		)
		(property "Device Type" "120R2F-GP_RCL_GP-120R2F-GP,64.A"
			(at 0.064008 -5.632196 180)
			(unlocked yes)
			(layer "F.Fab")
			(hide yes)
			(effects
				(font
					(size 1.27 1.016)
					(thickness 0.1524)
				)
			)
		)
		(duplicate_pad_numbers_are_jumpers no)
		(fp_line
			(start 0.508 -0.9398)
			(end -0.508 -0.9398)
			(stroke
				(width 0.1524)
				(type default)
			)
			(layer "F.SilkS")
		)
		(fp_line
			(start -0.508 -0.9398)
			(end -0.508 0.9398)
			(stroke
				(width 0.1524)
				(type default)
			)
			(layer "F.SilkS")
		)
		(fp_rect
			(start -0.508 0.9398)
			(end 0.508 -0.9398)
			(stroke
				(width 0)
				(type default)
			)
			(fill no)
			(layer "F.CrtYd")
		)
		(fp_rect
			(start -0.508 0.9398)
			(end 0.508 -0.9398)
			(stroke
				(width 0)
				(type default)
			)
			(fill no)
			(layer "F.Fab")
		)
		(pad "1" smd custom
			(at 0 -0.4445 180)
			(size 0.1397 0.1397)
			(layers "F.Cu" "F.Mask" "F.Paste")
			(net "BMC_M_A13")
			(options
				(clearance outline)
				(anchor circle)
			)
			(primitives
				(gr_poly
					(pts
						(arc
							(start -0.1778 -0.2794)
							(mid -0.249642 -0.249642)
							(end -0.2794 -0.1778)
						)
						(arc
							(start -0.2794 0.1778)
							(mid -0.249642 0.249642)
							(end -0.1778 0.2794)
						)
						(arc
							(start 0.1778 0.2794)
							(mid 0.249642 0.249642)
							(end 0.2794 0.1778)
						)
						(arc
							(start 0.2794 -0.1778)
							(mid 0.249642 -0.249642)
							(end 0.1778 -0.2794)
						)
					)
					(width 0)
					(fill yes)
				)
			)
		)
		(pad "2" smd custom
			(at 0 0.4445 180)
			(size 0.1397 0.1397)
			(layers "F.Cu" "F.Mask" "F.Paste")
			(net "P1V2_AUX_BMC")
			(options
				(clearance outline)
				(anchor circle)
			)
			(primitives
				(gr_poly
					(pts
						(arc
							(start -0.1778 -0.2794)
							(mid -0.249642 -0.249642)
							(end -0.2794 -0.1778)
						)
						(arc
							(start -0.2794 0.1778)
							(mid -0.249642 0.249642)
							(end -0.1778 0.2794)
						)
						(arc
							(start 0.1778 0.2794)
							(mid 0.249642 0.249642)
							(end 0.2794 0.1778)
						)
						(arc
							(start 0.2794 -0.1778)
							(mid 0.249642 -0.249642)
							(end 0.1778 -0.2794)
						)
					)
					(width 0)
					(fill yes)
				)
			)
		)
	)
)
